(kicad_pcb
	(version 20260206)
	(generator "pcbnew")
	(generator_version "10.0")
	(general
		(thickness 1.6)
		(legacy_teardrops no)
	)
	(paper "A4")
	(title_block
		(title "Bryce Canyon_R.DPB_16317-1_OCP.brd")
		(comment 1 "Bryce Canyon / footprints 635-640 of 2099")
	)
	(layers
		(0 "F.Cu" signal "TOP")
		(4 "In1.Cu" signal "L2GND")
		(6 "In2.Cu" signal "L3")
		(8 "In3.Cu" signal "L4VCC")
		(10 "In4.Cu" signal "L5VCC")
		(12 "In5.Cu" signal "L6")
		(14 "In6.Cu" signal "L7GND")
		(2 "B.Cu" signal "BOTTOM")
		(9 "F.Adhes" user "F.Adhesive")
		(11 "B.Adhes" user "B.Adhesive")
		(13 "F.Paste" user "Package Geometry/Pastemask Top")
		(15 "B.Paste" user "Package Geometry/Pastemask Bottom")
		(5 "F.SilkS" user "Ref Des/Silkscreen Top")
		(7 "B.SilkS" user "Ref Des/Silkscreen Bottom")
		(1 "F.Mask" user "Board Geometry/Soldermask Top")
		(3 "B.Mask" user "Board Geometry/Soldermask Bottom")
		(17 "Dwgs.User" user "User.Drawings")
		(19 "Cmts.User" user "User.Comments")
		(21 "Eco1.User" user "User.Eco1")
		(23 "Eco2.User" user "User.Eco2")
		(25 "Edge.Cuts" user "Board Geometry/Outline")
		(27 "Margin" user)
		(31 "F.CrtYd" user "Package Geometry/Place Bound Top")
		(29 "B.CrtYd" user "Package Geometry/Place Bound Bottom")
		(35 "F.Fab" user "Ref Des/Assembly Top")
		(33 "B.Fab" user "Ref Des/Assembly Bottom")
	)
	(footprint ""
		(layer "F.Cu")
		(at 370.205 -143.891 90)
		(property "Reference" "C286"
			(at 0 0 90)
			(layer "F.SilkS")
			(hide yes)
			(effects
				(font
					(size 1.27 1.27)
				)
			)
		)
		(property "Value" "SCD033U25V2KX-GP"
			(at 1.1811 -2.7051 90)
			(unlocked yes)
			(layer "F.Fab")
			(hide yes)
			(effects
				(font
					(size 1.016 1.016)
					(thickness 0.1524)
				)
			)
		)
		(property "Device Type" "C402H22"
			(at 1.1811 -4.2291 90)
			(unlocked yes)
			(layer "F.Fab")
			(hide yes)
			(effects
				(font
					(size 1.016 1.016)
					(thickness 0.1524)
				)
			)
		)
		(duplicate_pad_numbers_are_jumpers no)
		(fp_rect
			(start -0.4318 0.9525)
			(end 0.4318 -0.9525)
			(stroke
				(width 0)
				(type default)
			)
			(fill no)
			(layer "F.CrtYd")
		)
		(fp_rect
			(start -0.4318 0.9525)
			(end 0.4318 -0.9525)
			(stroke
				(width 0)
				(type default)
			)
			(fill no)
			(layer "F.Fab")
		)
		(pad "1" smd custom
			(at 0 -0.4445 90)
			(size 0.1524 0.1524)
			(layers "F.Cu" "F.Mask" "F.Paste")
			(net "P12V_B")
			(options
				(clearance outline)
				(anchor circle)
			)
			(primitives
				(gr_poly
					(pts
						(arc
							(start 0.3048 -0.2032)
							(mid 0.275042 -0.275042)
							(end 0.2032 -0.3048)
						)
						(arc
							(start -0.2032 -0.3048)
							(mid -0.275042 -0.275042)
							(end -0.3048 -0.2032)
						)
						(arc
							(start -0.3048 0.2032)
							(mid -0.275042 0.275042)
							(end -0.2032 0.3048)
						)
						(arc
							(start 0.2032 0.3048)
							(mid 0.275042 0.275042)
							(end 0.3048 0.2032)
						)
					)
					(width 0)
					(fill yes)
				)
			)
		)
		(pad "2" smd custom
			(at 0 0.4445 90)
			(size 0.1524 0.1524)
			(layers "F.Cu" "F.Mask" "F.Paste")
			(net "SW_HDD_N19")
			(options
				(clearance outline)
				(anchor circle)
			)
			(primitives
				(gr_poly
					(pts
						(arc
							(start 0.3048 -0.2032)
							(mid 0.275042 -0.275042)
							(end 0.2032 -0.3048)
						)
						(arc
							(start -0.2032 -0.3048)
							(mid -0.275042 -0.275042)
							(end -0.3048 -0.2032)
						)
						(arc
							(start -0.3048 0.2032)
							(mid -0.275042 0.275042)
							(end -0.2032 0.3048)
						)
						(arc
							(start 0.2032 0.3048)
							(mid 0.275042 0.275042)
							(end 0.3048 0.2032)
						)
					)
					(width 0)
					(fill yes)
				)
			)
		)
	)
	(footprint ""
		(layer "F.Cu")
		(at 233.72318 -219.03436)
		(property "Reference" "R67"
			(at 0 0 0)
			(layer "F.SilkS")
			(hide yes)
			(effects
				(font
					(size 1.27 1.27)
				)
			)
		)
		(property "Value" "0R2J-2-GP"
			(at 0.064008 -3.993896 0)
			(unlocked yes)
			(layer "F.Fab")
			(hide yes)
			(effects
				(font
					(size 1.016 1.016)
					(thickness 0.1524)
				)
			)
		)
		(property "Device Type" "R402H16"
			(at 0.064008 -5.517896 0)
			(unlocked yes)
			(layer "F.Fab")
			(hide yes)
			(effects
				(font
					(size 1.016 1.016)
					(thickness 0.1524)
				)
			)
		)
		(duplicate_pad_numbers_are_jumpers no)
		(fp_line
			(start -0.508 -0.9398)
			(end -0.508 0.9398)
			(stroke
				(width 0.1524)
				(type default)
			)
			(layer "F.SilkS")
		)
		(fp_line
			(start 0.508 -0.9398)
			(end -0.508 -0.9398)
			(stroke
				(width 0.1524)
				(type default)
			)
			(layer "F.SilkS")
		)
		(fp_rect
			(start -0.508 0.9398)
			(end 0.508 -0.9398)
			(stroke
				(width 0)
				(type default)
			)
			(fill no)
			(layer "F.CrtYd")
		)
		(fp_rect
			(start -0.508 0.9398)
			(end 0.508 -0.9398)
			(stroke
				(width 0)
				(type default)
			)
			(fill no)
			(layer "F.Fab")
		)
		(pad "1" smd custom
			(at 0 -0.4445)
			(size 0.1397 0.1397)
			(layers "F.Cu" "F.Mask" "F.Paste")
			(net "IO_EXP1_SCL")
			(options
				(clearance outline)
				(anchor circle)
			)
			(primitives
				(gr_poly
					(pts
						(arc
							(start -0.1778 -0.2794)
							(mid -0.249642 -0.249642)
							(end -0.2794 -0.1778)
						)
						(arc
							(start -0.2794 0.1778)
							(mid -0.249642 0.249642)
							(end -0.1778 0.2794)
						)
						(arc
							(start 0.1778 0.2794)
							(mid 0.249642 0.249642)
							(end 0.2794 0.1778)
						)
						(arc
							(start 0.2794 -0.1778)
							(mid 0.249642 -0.249642)
							(end 0.1778 -0.2794)
						)
					)
					(width 0)
					(fill yes)
				)
			)
		)
		(pad "2" smd custom
			(at 0 0.4445)
			(size 0.1397 0.1397)
			(layers "F.Cu" "F.Mask" "F.Paste")
			(net "I2C_DRIVE_B_PWR_SCL")
			(options
				(clearance outline)
				(anchor circle)
			)
			(primitives
				(gr_poly
					(pts
						(arc
							(start -0.1778 -0.2794)
							(mid -0.249642 -0.249642)
							(end -0.2794 -0.1778)
						)
						(arc
							(start -0.2794 0.1778)
							(mid -0.249642 0.249642)
							(end -0.1778 0.2794)
						)
						(arc
							(start 0.1778 0.2794)
							(mid 0.249642 0.249642)
							(end 0.2794 0.1778)
						)
						(arc
							(start 0.2794 -0.1778)
							(mid 0.249642 -0.249642)
							(end 0.1778 -0.2794)
						)
					)
					(width 0)
					(fill yes)
				)
			)
		)
	)
	(footprint ""
		(layer "F.Cu")
		(at 444.506096 -111.434118 -90)
		(property "Reference" "C682"
			(at 0 0 270)
			(layer "F.SilkS")
			(hide yes)
			(effects
				(font
					(size 1.27 1.27)
				)
			)
		)
		(property "Value" "SC2200P50V2KX-2GP"
			(at 1.1811 -2.7051 270)
			(unlocked yes)
			(layer "F.Fab")
			(hide yes)
			(effects
				(font
					(size 1.016 1.016)
					(thickness 0.1524)
				)
			)
		)
		(property "Device Type" "C402H22"
			(at 1.1811 -4.2291 270)
			(unlocked yes)
			(layer "F.Fab")
			(hide yes)
			(effects
				(font
					(size 1.016 1.016)
					(thickness 0.1524)
				)
			)
		)
		(duplicate_pad_numbers_are_jumpers no)
		(fp_rect
			(start -0.4318 0.9525)
			(end 0.4318 -0.9525)
			(stroke
				(width 0)
				(type default)
			)
			(fill no)
			(layer "F.CrtYd")
		)
		(fp_rect
			(start -0.4318 0.9525)
			(end 0.4318 -0.9525)
			(stroke
				(width 0)
				(type default)
			)
			(fill no)
			(layer "F.Fab")
		)
		(pad "1" smd custom
			(at 0 -0.4445 270)
			(size 0.1524 0.1524)
			(layers "F.Cu" "F.Mask" "F.Paste")
			(net "P5V_B_4_LL")
			(options
				(clearance outline)
				(anchor circle)
			)
			(primitives
				(gr_poly
					(pts
						(arc
							(start 0.3048 -0.2032)
							(mid 0.275042 -0.275042)
							(end 0.2032 -0.3048)
						)
						(arc
							(start -0.2032 -0.3048)
							(mid -0.275042 -0.275042)
							(end -0.3048 -0.2032)
						)
						(arc
							(start -0.3048 0.2032)
							(mid -0.275042 0.275042)
							(end -0.2032 0.3048)
						)
						(arc
							(start 0.2032 0.3048)
							(mid 0.275042 0.275042)
							(end 0.3048 0.2032)
						)
					)
					(width 0)
					(fill yes)
				)
			)
		)
		(pad "2" smd custom
			(at 0 0.4445 270)
			(size 0.1524 0.1524)
			(layers "F.Cu" "F.Mask" "F.Paste")
			(net "P5V_B_4_SNB")
			(options
				(clearance outline)
				(anchor circle)
			)
			(primitives
				(gr_poly
					(pts
						(arc
							(start 0.3048 -0.2032)
							(mid 0.275042 -0.275042)
							(end 0.2032 -0.3048)
						)
						(arc
							(start -0.2032 -0.3048)
							(mid -0.275042 -0.275042)
							(end -0.3048 -0.2032)
						)
						(arc
							(start -0.3048 0.2032)
							(mid -0.275042 0.275042)
							(end -0.2032 0.3048)
						)
						(arc
							(start 0.2032 0.3048)
							(mid 0.275042 0.275042)
							(end 0.3048 0.2032)
						)
					)
					(width 0)
					(fill yes)
				)
			)
		)
	)
	(footprint ""
		(layer "F.Cu")
		(at 170.307 -214.7062 180)
		(property "Reference" "Q224"
			(at 0 0 180)
			(layer "F.SilkS")
			(hide yes)
			(effects
				(font
					(size 1.27 1.27)
				)
			)
		)
		(property "Value" "2N7002K-2-GP"
			(at 0.127 -8.9662 180)
			(unlocked yes)
			(layer "F.Fab")
			(hide yes)
			(effects
				(font
					(size 1.016 1.016)
					(thickness 0.1524)
				)
			)
		)
		(property "Device Type" "SOT23DGS2D4H44"
			(at 0.127 -10.4902 180)
			(unlocked yes)
			(layer "F.Fab")
			(hide yes)
			(effects
				(font
					(size 1.016 1.016)
					(thickness 0.1524)
				)
			)
		)
		(duplicate_pad_numbers_are_jumpers no)
		(fp_line
			(start 1.651 1.778)
			(end 1.651 -1.778)
			(stroke
				(width 0.1524)
				(type default)
			)
			(layer "F.SilkS")
		)
		(fp_line
			(start 1.651 -1.778)
			(end -1.651 -1.778)
			(stroke
				(width 0.1524)
				(type default)
			)
			(layer "F.SilkS")
		)
		(fp_line
			(start -1.651 1.778)
			(end 1.651 1.778)
			(stroke
				(width 0.1524)
				(type default)
			)
			(layer "F.SilkS")
		)
		(fp_line
			(start -1.651 -1.778)
			(end -1.651 1.778)
			(stroke
				(width 0.1524)
				(type default)
			)
			(layer "F.SilkS")
		)
		(fp_poly
			(pts
				(xy -1.778 1.8796) (xy -1.778 -1.8796) (xy 1.778 -1.8796) (xy 1.778 1.8796)
			)
			(stroke
				(width 0)
				(type default)
			)
			(fill no)
			(layer "F.CrtYd")
		)
		(fp_poly
			(pts
				(xy -1.778 1.8796) (xy -1.778 -1.8796) (xy 1.778 -1.8796) (xy 1.778 1.8796)
			)
			(stroke
				(width 0)
				(type default)
			)
			(fill no)
			(layer "F.Fab")
		)
		(pad "D" smd custom
			(at 0 -0.9525 180)
			(size 0.1905 0.1905)
			(layers "F.Cu" "F.Mask" "F.Paste")
			(net "FLT_HDD5_N")
			(options
				(clearance outline)
				(anchor circle)
			)
			(primitives
				(gr_poly
					(pts
						(arc
							(start -0.1778 0.5715)
							(mid -0.321484 0.511984)
							(end -0.381 0.3683)
						)
						(arc
							(start -0.381 -0.3683)
							(mid -0.321484 -0.511984)
							(end -0.1778 -0.5715)
						)
						(arc
							(start 0.1778 -0.5715)
							(mid 0.321484 -0.511984)
							(end 0.381 -0.3683)
						)
						(arc
							(start 0.381 0.3683)
							(mid 0.321484 0.511984)
							(end 0.1778 0.5715)
						)
					)
					(width 0)
					(fill yes)
				)
			)
		)
		(pad "G" smd custom
			(at -0.98425 0.9525 180)
			(size 0.1905 0.1905)
			(layers "F.Cu" "F.Mask" "F.Paste")
			(net "DRIVE_B_5_FLT_LED")
			(options
				(clearance outline)
				(anchor circle)
			)
			(primitives
				(gr_poly
					(pts
						(arc
							(start -0.1778 0.5715)
							(mid -0.321484 0.511984)
							(end -0.381 0.3683)
						)
						(arc
							(start -0.381 -0.3683)
							(mid -0.321484 -0.511984)
							(end -0.1778 -0.5715)
						)
						(arc
							(start 0.1778 -0.5715)
							(mid 0.321484 -0.511984)
							(end 0.381 -0.3683)
						)
						(arc
							(start 0.381 0.3683)
							(mid 0.321484 0.511984)
							(end 0.1778 0.5715)
						)
					)
					(width 0)
					(fill yes)
				)
			)
		)
		(pad "S" smd custom
			(at 0.98425 0.9525 180)
			(size 0.1905 0.1905)
			(layers "F.Cu" "F.Mask" "F.Paste")
			(net "GND")
			(options
				(clearance outline)
				(anchor circle)
			)
			(primitives
				(gr_poly
					(pts
						(arc
							(start -0.1778 0.5715)
							(mid -0.321484 0.511984)
							(end -0.381 0.3683)
						)
						(arc
							(start -0.381 -0.3683)
							(mid -0.321484 -0.511984)
							(end -0.1778 -0.5715)
						)
						(arc
							(start 0.1778 -0.5715)
							(mid 0.321484 -0.511984)
							(end 0.381 -0.3683)
						)
						(arc
							(start 0.381 0.3683)
							(mid 0.321484 0.511984)
							(end 0.1778 0.5715)
						)
					)
					(width 0)
					(fill yes)
				)
			)
		)
	)
	(footprint ""
		(layer "F.Cu")
		(at 109.474 -246.634 90)
		(property "Reference" "R216"
			(at 0 0 90)
			(layer "F.SilkS")
			(hide yes)
			(effects
				(font
					(size 1.27 1.27)
				)
			)
		)
		(property "Value" "4K7R2J-2-GP"
			(at 0.064008 -3.993896 90)
			(unlocked yes)
			(layer "F.Fab")
			(hide yes)
			(effects
				(font
					(size 1.016 1.016)
					(thickness 0.1524)
				)
			)
		)
		(property "Device Type" "R402H16"
			(at 0.064008 -5.517896 90)
			(unlocked yes)
			(layer "F.Fab")
			(hide yes)
			(effects
				(font
					(size 1.016 1.016)
					(thickness 0.1524)
				)
			)
		)
		(duplicate_pad_numbers_are_jumpers no)
		(fp_line
			(start 0.508 -0.9398)
			(end -0.508 -0.9398)
			(stroke
				(width 0.1524)
				(type default)
			)
			(layer "F.SilkS")
		)
		(fp_line
			(start -0.508 -0.9398)
			(end -0.508 0.9398)
			(stroke
				(width 0.1524)
				(type default)
			)
			(layer "F.SilkS")
		)
		(fp_rect
			(start -0.508 0.9398)
			(end 0.508 -0.9398)
			(stroke
				(width 0)
				(type default)
			)
			(fill no)
			(layer "F.CrtYd")
		)
		(fp_rect
			(start -0.508 0.9398)
			(end 0.508 -0.9398)
			(stroke
				(width 0)
				(type default)
			)
			(fill no)
			(layer "F.Fab")
		)
		(pad "1" smd custom
			(at 0 -0.4445 90)
			(size 0.1397 0.1397)
			(layers "F.Cu" "F.Mask" "F.Paste")
			(net "P12V_B")
			(options
				(clearance outline)
				(anchor circle)
			)
			(primitives
				(gr_poly
					(pts
						(arc
							(start -0.1778 -0.2794)
							(mid -0.249642 -0.249642)
							(end -0.2794 -0.1778)
						)
						(arc
							(start -0.2794 0.1778)
							(mid -0.249642 0.249642)
							(end -0.1778 0.2794)
						)
						(arc
							(start 0.1778 0.2794)
							(mid 0.249642 0.249642)
							(end 0.2794 0.1778)
						)
						(arc
							(start 0.2794 -0.1778)
							(mid 0.249642 -0.249642)
							(end 0.1778 -0.2794)
						)
					)
					(width 0)
					(fill yes)
				)
			)
		)
		(pad "2" smd custom
			(at 0 0.4445 90)
			(size 0.1397 0.1397)
			(layers "F.Cu" "F.Mask" "F.Paste")
			(net "SW_HDD_R3")
			(options
				(clearance outline)
				(anchor circle)
			)
			(primitives
				(gr_poly
					(pts
						(arc
							(start -0.1778 -0.2794)
							(mid -0.249642 -0.249642)
							(end -0.2794 -0.1778)
						)
						(arc
							(start -0.2794 0.1778)
							(mid -0.249642 0.249642)
							(end -0.1778 0.2794)
						)
						(arc
							(start 0.1778 0.2794)
							(mid 0.249642 0.249642)
							(end 0.2794 0.1778)
						)
						(arc
							(start 0.2794 -0.1778)
							(mid 0.249642 -0.249642)
							(end 0.1778 -0.2794)
						)
					)
					(width 0)
					(fill yes)
				)
			)
		)
	)
	(footprint ""
		(layer "F.Cu")
		(at 77.978 -145.796)
		(property "Reference" "Q60"
			(at 0 0 0)
			(layer "F.SilkS")
			(hide yes)
			(effects
				(font
					(size 1.27 1.27)
				)
			)
		)
		(property "Value" "AO4407AL-GP"
			(at -3.707384 -1.5367 0)
			(unlocked yes)
			(layer "F.Fab")
			(hide yes)
			(effects
				(font
					(size 1.016 1.016)
					(thickness 0.1524)
				)
			)
		)
		(property "Device Type" "SOIC8H69"
			(at -3.707384 -3.0607 0)
			(unlocked yes)
			(layer "F.Fab")
			(hide yes)
			(effects
				(font
					(size 1.016 1.016)
					(thickness 0.1524)
				)
			)
		)
		(duplicate_pad_numbers_are_jumpers no)
		(fp_line
			(start -2.7432 -1.4224)
			(end -2.7432 1.4224)
			(stroke
				(width 0.1524)
				(type default)
			)
			(layer "F.SilkS")
		)
		(fp_line
			(start -2.7432 1.4224)
			(end -2.6416 1.4224)
			(stroke
				(width 0.1524)
				(type default)
			)
			(layer "F.SilkS")
		)
		(fp_line
			(start -2.7432 1.4224)
			(end 2.1336 1.4224)
			(stroke
				(width 0.1524)
				(type default)
			)
			(layer "F.SilkS")
		)
		(fp_line
			(start -2.7178 -0.508)
			(end -2.1844 -0.0508)
			(stroke
				(width 0.1524)
				(type default)
			)
			(layer "F.SilkS")
		)
		(fp_line
			(start -2.6289 3.4417)
			(end -2.6289 1.4732)
			(stroke
				(width 0.381)
				(type default)
			)
			(layer "F.SilkS")
		)
		(fp_line
			(start -2.1844 -0.0508)
			(end -2.7178 0.508)
			(stroke
				(width 0.1524)
				(type default)
			)
			(layer "F.SilkS")
		)
		(fp_line
			(start 2.1336 -1.4224)
			(end -2.7432 -1.4224)
			(stroke
				(width 0.1524)
				(type default)
			)
			(layer "F.SilkS")
		)
		(fp_line
			(start 2.1336 1.4224)
			(end 2.1336 -1.4224)
			(stroke
				(width 0.1524)
				(type default)
			)
			(layer "F.SilkS")
		)
		(fp_poly
			(pts
				(xy -2.2098 -1.4224) (xy -2.2098 1.4224) (xy 2.2098 1.4224) (xy 2.2098 -1.4224)
			)
			(stroke
				(width 0)
				(type default)
			)
			(fill yes)
			(layer "F.SilkS")
		)
		(fp_rect
			(start -2.450084 2.999994)
			(end 2.450084 -2.999994)
			(stroke
				(width 0)
				(type default)
			)
			(fill no)
			(layer "F.CrtYd")
		)
		(fp_poly
			(pts
				(xy -2.8194 3.6322) (xy -2.8194 -3.6322) (xy 2.8194 -3.6322) (xy 2.8194 1.18364) (xy 2.450084 1.18364)
				(xy 2.450084 -2.999994) (xy -2.450084 -2.999994) (xy -2.450084 2.999994) (xy 2.450084 2.999994)
				(xy 2.450084 1.18618) (xy 2.8194 1.18618) (xy 2.8194 3.6322)
			)
			(stroke
				(width 0)
				(type default)
			)
			(fill no)
			(layer "F.CrtYd")
		)
		(fp_rect
			(start -2.8194 3.6322)
			(end 2.8194 -3.6322)
			(stroke
				(width 0)
				(type default)
			)
			(fill no)
			(layer "F.Fab")
		)
		(pad "1" smd rect
			(at -1.905 2.54)
			(size 0.635 1.651)
			(layers "F.Cu" "F.Mask" "F.Paste")
			(net "P12V_B")
		)
		(pad "2" smd rect
			(at -0.635 2.54)
			(size 0.635 1.651)
			(layers "F.Cu" "F.Mask" "F.Paste")
			(net "P12V_B")
		)
		(pad "3" smd rect
			(at 0.635 2.54)
			(size 0.635 1.651)
			(layers "F.Cu" "F.Mask" "F.Paste")
			(net "P12V_B")
		)
		(pad "4" smd rect
			(at 1.905 2.54)
			(size 0.635 1.651)
			(layers "F.Cu" "F.Mask" "F.Paste")
			(net "SW_HDD_N14")
		)
		(pad "5" smd rect
			(at 1.905 -2.54)
			(size 0.635 1.651)
			(layers "F.Cu" "F.Mask" "F.Paste")
			(net "P12V_HDD14")
		)
		(pad "6" smd rect
			(at 0.635 -2.54)
			(size 0.635 1.651)
			(layers "F.Cu" "F.Mask" "F.Paste")
			(net "P12V_HDD14")
		)
		(pad "7" smd rect
			(at -0.635 -2.54)
			(size 0.635 1.651)
			(layers "F.Cu" "F.Mask" "F.Paste")
			(net "P12V_HDD14")
		)
		(pad "8" smd rect
			(at -1.905 -2.54)
			(size 0.635 1.651)
			(layers "F.Cu" "F.Mask" "F.Paste")
			(net "P12V_HDD14")
		)
	)
)
